(kicad_pcb
	(version 20260206)
	(generator "pcbnew")
	(generator_version "10.0")
	(general
		(thickness 1.6)
		(legacy_teardrops no)
	)
	(paper "A4")
	(title_block
		(title "01162023_DA0F0TEBIF0_F0T_Expander_BD_F_brd_V02_OCP.brd")
		(comment 1 "Grand Teton / footprints 630-636 of 9728")
	)
	(layers
		(0 "F.Cu" signal "TOP")
		(4 "In1.Cu" signal "GND")
		(6 "In2.Cu" signal "VCC")
		(8 "In3.Cu" signal "VCC1")
		(10 "In4.Cu" signal "GND1")
		(12 "In5.Cu" signal "IN1")
		(14 "In6.Cu" signal "GND2")
		(16 "In7.Cu" signal "IN2")
		(18 "In8.Cu" signal "GND3")
		(20 "In9.Cu" signal "IN3")
		(22 "In10.Cu" signal "GND4")
		(24 "In11.Cu" signal "IN4")
		(26 "In12.Cu" signal "GND5")
		(28 "In13.Cu" signal "IN5")
		(30 "In14.Cu" signal "GND6")
		(32 "In15.Cu" signal "IN6")
		(34 "In16.Cu" signal "GND7")
		(2 "B.Cu" signal "BOTTOM")
		(9 "F.Adhes" user "F.Adhesive")
		(11 "B.Adhes" user "B.Adhesive")
		(13 "F.Paste" user "Package Geometry/Pastemask Top")
		(15 "B.Paste" user "Package Geometry/Pastemask Bottom")
		(5 "F.SilkS" user "Ref Des/Silkscreen Top")
		(7 "B.SilkS" user "Ref Des/Silkscreen Bottom")
		(1 "F.Mask" user "Board Geometry/Soldermask Top")
		(3 "B.Mask" user "Board Geometry/Soldermask Bottom")
		(17 "Dwgs.User" user "User.Drawings")
		(19 "Cmts.User" user "User.Comments")
		(21 "Eco1.User" user "User.Eco1")
		(23 "Eco2.User" user "User.Eco2")
		(25 "Edge.Cuts" user "Board Geometry/Outline")
		(27 "Margin" user)
		(31 "F.CrtYd" user "Package Geometry/Place Bound Top")
		(29 "B.CrtYd" user "Package Geometry/Place Bound Bottom")
		(35 "F.Fab" user "Ref Des/Assembly Top")
		(33 "B.Fab" user "Ref Des/Assembly Bottom")
	)
	(footprint ""
		(layer "F.Cu")
		(at 462.465674 -273.59483)
		(property "Reference" "R802"
			(at 0 0 0)
			(layer "F.SilkS")
			(hide yes)
			(effects
				(font
					(size 1.27 1.27)
				)
			)
		)
		(property "Value" ""
			(at 0 0 0)
			(layer "F.Fab")
			(effects
				(font
					(size 1.27 1.27)
				)
			)
		)
		(duplicate_pad_numbers_are_jumpers no)
		(fp_line
			(start -0.7874 -0.4064)
			(end 0.7874 -0.4064)
			(stroke
				(width 0.1524)
				(type default)
			)
			(layer "F.SilkS")
		)
		(fp_line
			(start -0.7874 0.4064)
			(end -0.7874 -0.4064)
			(stroke
				(width 0.1524)
				(type default)
			)
			(layer "F.SilkS")
		)
		(fp_line
			(start 0.7874 -0.4064)
			(end 0.7874 0.4064)
			(stroke
				(width 0.1524)
				(type default)
			)
			(layer "F.SilkS")
		)
		(fp_line
			(start 0.7874 0.4064)
			(end -0.7874 0.4064)
			(stroke
				(width 0.1524)
				(type default)
			)
			(layer "F.SilkS")
		)
		(fp_line
			(start -0.67945 -0.305054)
			(end -0.12065 -0.305054)
			(stroke
				(width 0.1)
				(type default)
			)
			(layer "F.Fab")
		)
		(fp_line
			(start -0.67945 0.3048)
			(end -0.67945 -0.305054)
			(stroke
				(width 0.1)
				(type default)
			)
			(layer "F.Fab")
		)
		(fp_line
			(start -0.12065 -0.305054)
			(end -0.12065 -0.2794)
			(stroke
				(width 0.1)
				(type default)
			)
			(layer "F.Fab")
		)
		(fp_line
			(start -0.12065 -0.2794)
			(end 0.12065 -0.2794)
			(stroke
				(width 0.1)
				(type default)
			)
			(layer "F.Fab")
		)
		(fp_line
			(start -0.12065 0.2794)
			(end -0.12065 0.3048)
			(stroke
				(width 0.1)
				(type default)
			)
			(layer "F.Fab")
		)
		(fp_line
			(start -0.12065 0.3048)
			(end -0.67945 0.3048)
			(stroke
				(width 0.1)
				(type default)
			)
			(layer "F.Fab")
		)
		(fp_line
			(start 0.120396 0.2794)
			(end -0.12065 0.2794)
			(stroke
				(width 0.1)
				(type default)
			)
			(layer "F.Fab")
		)
		(fp_line
			(start 0.120396 0.3048)
			(end 0.120396 0.2794)
			(stroke
				(width 0.1)
				(type default)
			)
			(layer "F.Fab")
		)
		(fp_line
			(start 0.12065 -0.3048)
			(end 0.67945 -0.3048)
			(stroke
				(width 0.1)
				(type default)
			)
			(layer "F.Fab")
		)
		(fp_line
			(start 0.12065 -0.2794)
			(end 0.12065 -0.3048)
			(stroke
				(width 0.1)
				(type default)
			)
			(layer "F.Fab")
		)
		(fp_line
			(start 0.67945 -0.3048)
			(end 0.67945 0.3048)
			(stroke
				(width 0.1)
				(type default)
			)
			(layer "F.Fab")
		)
		(fp_line
			(start 0.67945 0.3048)
			(end 0.120396 0.3048)
			(stroke
				(width 0.1)
				(type default)
			)
			(layer "F.Fab")
		)
		(pad "1" smd circle
			(at -0.40005 0)
			(size 0 0)
			(layers "F.Cu" "F.Mask" "F.Paste")
			(net "PEX3_P1V25_ADC_A1")
		)
		(pad "2" smd circle
			(at 0.40005 0)
			(size 0 0)
			(layers "F.Cu" "F.Mask" "F.Paste")
			(net "P3V3_AUX")
		)
	)
	(footprint ""
		(layer "F.Cu")
		(at 98.866198 -95.263716 -90)
		(property "Reference" "PC456"
			(at 0 0 270)
			(layer "F.SilkS")
			(hide yes)
			(effects
				(font
					(size 1.27 1.27)
				)
			)
		)
		(property "Value" ""
			(at 0 0 270)
			(layer "F.Fab")
			(effects
				(font
					(size 1.27 1.27)
				)
			)
		)
		(duplicate_pad_numbers_are_jumpers no)
		(fp_line
			(start -0.7874 0.4064)
			(end -0.7874 -0.4064)
			(stroke
				(width 0.1524)
				(type default)
			)
			(layer "F.SilkS")
		)
		(fp_line
			(start 0.7874 0.4064)
			(end -0.7874 0.4064)
			(stroke
				(width 0.1524)
				(type default)
			)
			(layer "F.SilkS")
		)
		(fp_line
			(start -0.7874 -0.4064)
			(end 0.7874 -0.4064)
			(stroke
				(width 0.1524)
				(type default)
			)
			(layer "F.SilkS")
		)
		(fp_line
			(start 0.7874 -0.4064)
			(end 0.7874 0.4064)
			(stroke
				(width 0.1524)
				(type default)
			)
			(layer "F.SilkS")
		)
		(fp_line
			(start -0.67945 0.3048)
			(end -0.67945 -0.305054)
			(stroke
				(width 0.1)
				(type default)
			)
			(layer "F.Fab")
		)
		(fp_line
			(start -0.12065 0.3048)
			(end -0.67945 0.3048)
			(stroke
				(width 0.1)
				(type default)
			)
			(layer "F.Fab")
		)
		(fp_line
			(start 0.120396 0.3048)
			(end 0.120396 0.2794)
			(stroke
				(width 0.1)
				(type default)
			)
			(layer "F.Fab")
		)
		(fp_line
			(start 0.67945 0.3048)
			(end 0.120396 0.3048)
			(stroke
				(width 0.1)
				(type default)
			)
			(layer "F.Fab")
		)
		(fp_line
			(start -0.12065 0.2794)
			(end -0.12065 0.3048)
			(stroke
				(width 0.1)
				(type default)
			)
			(layer "F.Fab")
		)
		(fp_line
			(start 0.120396 0.2794)
			(end -0.12065 0.2794)
			(stroke
				(width 0.1)
				(type default)
			)
			(layer "F.Fab")
		)
		(fp_line
			(start -0.12065 -0.2794)
			(end 0.12065 -0.2794)
			(stroke
				(width 0.1)
				(type default)
			)
			(layer "F.Fab")
		)
		(fp_line
			(start 0.12065 -0.2794)
			(end 0.12065 -0.3048)
			(stroke
				(width 0.1)
				(type default)
			)
			(layer "F.Fab")
		)
		(fp_line
			(start 0.12065 -0.3048)
			(end 0.67945 -0.3048)
			(stroke
				(width 0.1)
				(type default)
			)
			(layer "F.Fab")
		)
		(fp_line
			(start 0.67945 -0.3048)
			(end 0.67945 0.3048)
			(stroke
				(width 0.1)
				(type default)
			)
			(layer "F.Fab")
		)
		(fp_line
			(start -0.67945 -0.305054)
			(end -0.12065 -0.305054)
			(stroke
				(width 0.1)
				(type default)
			)
			(layer "F.Fab")
		)
		(fp_line
			(start -0.12065 -0.305054)
			(end -0.12065 -0.2794)
			(stroke
				(width 0.1)
				(type default)
			)
			(layer "F.Fab")
		)
		(pad "1" smd circle
			(at -0.40005 0 270)
			(size 0 0)
			(layers "F.Cu" "F.Mask" "F.Paste")
			(net "P5V_AUX")
		)
		(pad "2" smd circle
			(at 0.40005 0 270)
			(size 0 0)
			(layers "F.Cu" "F.Mask" "F.Paste")
			(net "GND")
		)
	)
	(footprint ""
		(layer "F.Cu")
		(at 225.530664 -204.44206 90)
		(property "Reference" "R5280"
			(at 0 0 90)
			(layer "F.SilkS")
			(hide yes)
			(effects
				(font
					(size 1.27 1.27)
				)
			)
		)
		(property "Value" ""
			(at 0 0 90)
			(layer "F.Fab")
			(effects
				(font
					(size 1.27 1.27)
				)
			)
		)
		(duplicate_pad_numbers_are_jumpers no)
		(fp_line
			(start 0.7874 -0.4064)
			(end 0.7874 0.4064)
			(stroke
				(width 0.1524)
				(type default)
			)
			(layer "F.SilkS")
		)
		(fp_line
			(start -0.7874 -0.4064)
			(end 0.7874 -0.4064)
			(stroke
				(width 0.1524)
				(type default)
			)
			(layer "F.SilkS")
		)
		(fp_line
			(start 0.7874 0.4064)
			(end -0.7874 0.4064)
			(stroke
				(width 0.1524)
				(type default)
			)
			(layer "F.SilkS")
		)
		(fp_line
			(start -0.7874 0.4064)
			(end -0.7874 -0.4064)
			(stroke
				(width 0.1524)
				(type default)
			)
			(layer "F.SilkS")
		)
		(fp_line
			(start -0.12065 -0.305054)
			(end -0.12065 -0.2794)
			(stroke
				(width 0.1)
				(type default)
			)
			(layer "F.Fab")
		)
		(fp_line
			(start -0.67945 -0.305054)
			(end -0.12065 -0.305054)
			(stroke
				(width 0.1)
				(type default)
			)
			(layer "F.Fab")
		)
		(fp_line
			(start 0.67945 -0.3048)
			(end 0.67945 0.3048)
			(stroke
				(width 0.1)
				(type default)
			)
			(layer "F.Fab")
		)
		(fp_line
			(start 0.12065 -0.3048)
			(end 0.67945 -0.3048)
			(stroke
				(width 0.1)
				(type default)
			)
			(layer "F.Fab")
		)
		(fp_line
			(start 0.12065 -0.2794)
			(end 0.12065 -0.3048)
			(stroke
				(width 0.1)
				(type default)
			)
			(layer "F.Fab")
		)
		(fp_line
			(start -0.12065 -0.2794)
			(end 0.12065 -0.2794)
			(stroke
				(width 0.1)
				(type default)
			)
			(layer "F.Fab")
		)
		(fp_line
			(start 0.120396 0.2794)
			(end -0.12065 0.2794)
			(stroke
				(width 0.1)
				(type default)
			)
			(layer "F.Fab")
		)
		(fp_line
			(start -0.12065 0.2794)
			(end -0.12065 0.3048)
			(stroke
				(width 0.1)
				(type default)
			)
			(layer "F.Fab")
		)
		(fp_line
			(start 0.67945 0.3048)
			(end 0.120396 0.3048)
			(stroke
				(width 0.1)
				(type default)
			)
			(layer "F.Fab")
		)
		(fp_line
			(start 0.120396 0.3048)
			(end 0.120396 0.2794)
			(stroke
				(width 0.1)
				(type default)
			)
			(layer "F.Fab")
		)
		(fp_line
			(start -0.12065 0.3048)
			(end -0.67945 0.3048)
			(stroke
				(width 0.1)
				(type default)
			)
			(layer "F.Fab")
		)
		(fp_line
			(start -0.67945 0.3048)
			(end -0.67945 -0.305054)
			(stroke
				(width 0.1)
				(type default)
			)
			(layer "F.Fab")
		)
		(pad "1" smd circle
			(at -0.40005 0 90)
			(size 0 0)
			(layers "F.Cu" "F.Mask" "F.Paste")
			(net "P3V3_AUX")
		)
		(pad "2" smd circle
			(at 0.40005 0 90)
			(size 0 0)
			(layers "F.Cu" "F.Mask" "F.Paste")
			(net "JTAG_BIC_NTRST_R_N")
		)
	)
	(footprint ""
		(layer "F.Cu")
		(at 391.085832 -89.421462)
		(property "Reference" "C2743"
			(at 0 0 0)
			(layer "F.SilkS")
			(hide yes)
			(effects
				(font
					(size 1.27 1.27)
				)
			)
		)
		(property "Value" ""
			(at 0 0 0)
			(layer "F.Fab")
			(effects
				(font
					(size 1.27 1.27)
				)
			)
		)
		(duplicate_pad_numbers_are_jumpers no)
		(fp_line
			(start -0.7874 -0.4064)
			(end 0.7874 -0.4064)
			(stroke
				(width 0.1524)
				(type default)
			)
			(layer "F.SilkS")
		)
		(fp_line
			(start -0.7874 0.4064)
			(end -0.7874 -0.4064)
			(stroke
				(width 0.1524)
				(type default)
			)
			(layer "F.SilkS")
		)
		(fp_line
			(start 0.7874 -0.4064)
			(end 0.7874 0.4064)
			(stroke
				(width 0.1524)
				(type default)
			)
			(layer "F.SilkS")
		)
		(fp_line
			(start 0.7874 0.4064)
			(end -0.7874 0.4064)
			(stroke
				(width 0.1524)
				(type default)
			)
			(layer "F.SilkS")
		)
		(fp_line
			(start -0.67945 -0.305054)
			(end -0.12065 -0.305054)
			(stroke
				(width 0.1)
				(type default)
			)
			(layer "F.Fab")
		)
		(fp_line
			(start -0.67945 0.3048)
			(end -0.67945 -0.305054)
			(stroke
				(width 0.1)
				(type default)
			)
			(layer "F.Fab")
		)
		(fp_line
			(start -0.12065 -0.305054)
			(end -0.12065 -0.2794)
			(stroke
				(width 0.1)
				(type default)
			)
			(layer "F.Fab")
		)
		(fp_line
			(start -0.12065 -0.2794)
			(end 0.12065 -0.2794)
			(stroke
				(width 0.1)
				(type default)
			)
			(layer "F.Fab")
		)
		(fp_line
			(start -0.12065 0.2794)
			(end -0.12065 0.3048)
			(stroke
				(width 0.1)
				(type default)
			)
			(layer "F.Fab")
		)
		(fp_line
			(start -0.12065 0.3048)
			(end -0.67945 0.3048)
			(stroke
				(width 0.1)
				(type default)
			)
			(layer "F.Fab")
		)
		(fp_line
			(start 0.120396 0.2794)
			(end -0.12065 0.2794)
			(stroke
				(width 0.1)
				(type default)
			)
			(layer "F.Fab")
		)
		(fp_line
			(start 0.120396 0.3048)
			(end 0.120396 0.2794)
			(stroke
				(width 0.1)
				(type default)
			)
			(layer "F.Fab")
		)
		(fp_line
			(start 0.12065 -0.3048)
			(end 0.67945 -0.3048)
			(stroke
				(width 0.1)
				(type default)
			)
			(layer "F.Fab")
		)
		(fp_line
			(start 0.12065 -0.2794)
			(end 0.12065 -0.3048)
			(stroke
				(width 0.1)
				(type default)
			)
			(layer "F.Fab")
		)
		(fp_line
			(start 0.67945 -0.3048)
			(end 0.67945 0.3048)
			(stroke
				(width 0.1)
				(type default)
			)
			(layer "F.Fab")
		)
		(fp_line
			(start 0.67945 0.3048)
			(end 0.120396 0.3048)
			(stroke
				(width 0.1)
				(type default)
			)
			(layer "F.Fab")
		)
		(pad "1" smd circle
			(at -0.40005 0)
			(size 0 0)
			(layers "F.Cu" "F.Mask" "F.Paste")
			(net "P3V3_AUX")
		)
		(pad "2" smd circle
			(at 0.40005 0)
			(size 0 0)
			(layers "F.Cu" "F.Mask" "F.Paste")
			(net "GND")
		)
	)
	(footprint ""
		(layer "F.Cu")
		(at 132.034026 -135.77697 -90)
		(property "Reference" "PC333"
			(at 0 0 270)
			(layer "F.SilkS")
			(hide yes)
			(effects
				(font
					(size 1.27 1.27)
				)
			)
		)
		(property "Value" ""
			(at 0 0 270)
			(layer "F.Fab")
			(effects
				(font
					(size 1.27 1.27)
				)
			)
		)
		(duplicate_pad_numbers_are_jumpers no)
		(fp_line
			(start -1.524 0.762)
			(end -1.524 -0.762)
			(stroke
				(width 0.1524)
				(type default)
			)
			(layer "F.SilkS")
		)
		(fp_line
			(start 1.524 0.762)
			(end -1.524 0.762)
			(stroke
				(width 0.1524)
				(type default)
			)
			(layer "F.SilkS")
		)
		(fp_line
			(start -1.524 -0.762)
			(end 1.524 -0.762)
			(stroke
				(width 0.1524)
				(type default)
			)
			(layer "F.SilkS")
		)
		(fp_line
			(start 1.524 -0.762)
			(end 1.524 0.762)
			(stroke
				(width 0.1524)
				(type default)
			)
			(layer "F.SilkS")
		)
		(fp_line
			(start -1.1049 0.724916)
			(end 1.1049 0.724916)
			(stroke
				(width 0.1)
				(type default)
			)
			(layer "F.Fab")
		)
		(fp_line
			(start 1.1049 0.724916)
			(end 1.1049 -0.724916)
			(stroke
				(width 0.1)
				(type default)
			)
			(layer "F.Fab")
		)
		(fp_line
			(start -1.1049 -0.724916)
			(end -1.1049 0.724916)
			(stroke
				(width 0.1)
				(type default)
			)
			(layer "F.Fab")
		)
		(fp_line
			(start 1.1049 -0.724916)
			(end -1.1049 -0.724916)
			(stroke
				(width 0.1)
				(type default)
			)
			(layer "F.Fab")
		)
		(pad "1" smd rect
			(at -0.889 0 90)
			(size 1.016 1.27)
			(layers "F.Cu" "F.Mask" "F.Paste")
			(net "P12V_NIC2_R")
		)
		(pad "2" smd rect
			(at 0.889 0 90)
			(size 1.016 1.27)
			(layers "F.Cu" "F.Mask" "F.Paste")
			(net "GND")
		)
	)
	(footprint ""
		(layer "F.Cu")
		(at 39.280592 -124.605542)
		(property "Reference" "C41"
			(at 0 0 0)
			(layer "F.SilkS")
			(hide yes)
			(effects
				(font
					(size 1.27 1.27)
				)
			)
		)
		(property "Value" ""
			(at 0 0 0)
			(layer "F.Fab")
			(effects
				(font
					(size 1.27 1.27)
				)
			)
		)
		(duplicate_pad_numbers_are_jumpers no)
		(fp_line
			(start -0.299974 -0.150114)
			(end 0.299974 -0.150114)
			(stroke
				(width 0.1)
				(type default)
			)
			(layer "F.Fab")
		)
		(fp_line
			(start -0.299974 0.150114)
			(end -0.299974 -0.150114)
			(stroke
				(width 0.1)
				(type default)
			)
			(layer "F.Fab")
		)
		(fp_line
			(start 0.299974 -0.150114)
			(end 0.299974 0.150114)
			(stroke
				(width 0.1)
				(type default)
			)
			(layer "F.Fab")
		)
		(fp_line
			(start 0.299974 0.150114)
			(end -0.299974 0.150114)
			(stroke
				(width 0.1)
				(type default)
			)
			(layer "F.Fab")
		)
		(pad "1" smd rect
			(at -0.2667 0)
			(size 0.3048 0.381)
			(layers "F.Cu" "F.Mask" "F.Paste")
			(net "P5E_PEX0_STN1_TX_DN<27>")
		)
		(pad "2" smd rect
			(at 0.2667 0)
			(size 0.3048 0.381)
			(layers "F.Cu" "F.Mask" "F.Paste")
			(net "P5E_PEX0_STN1_TX_C_DN<27>")
		)
	)
	(footprint ""
		(layer "F.Cu")
		(at 121.108978 -89.53373)
		(property "Reference" "R1560"
			(at 0 0 0)
			(layer "F.SilkS")
			(hide yes)
			(effects
				(font
					(size 1.27 1.27)
				)
			)
		)
		(property "Value" ""
			(at 0 0 0)
			(layer "F.Fab")
			(effects
				(font
					(size 1.27 1.27)
				)
			)
		)
		(duplicate_pad_numbers_are_jumpers no)
		(fp_line
			(start -0.7874 -0.4064)
			(end 0.7874 -0.4064)
			(stroke
				(width 0.1524)
				(type default)
			)
			(layer "F.SilkS")
		)
		(fp_line
			(start -0.7874 0.4064)
			(end -0.7874 -0.4064)
			(stroke
				(width 0.1524)
				(type default)
			)
			(layer "F.SilkS")
		)
		(fp_line
			(start 0.7874 -0.4064)
			(end 0.7874 0.4064)
			(stroke
				(width 0.1524)
				(type default)
			)
			(layer "F.SilkS")
		)
		(fp_line
			(start 0.7874 0.4064)
			(end -0.7874 0.4064)
			(stroke
				(width 0.1524)
				(type default)
			)
			(layer "F.SilkS")
		)
		(fp_line
			(start -0.67945 -0.305054)
			(end -0.12065 -0.305054)
			(stroke
				(width 0.1)
				(type default)
			)
			(layer "F.Fab")
		)
		(fp_line
			(start -0.67945 0.3048)
			(end -0.67945 -0.305054)
			(stroke
				(width 0.1)
				(type default)
			)
			(layer "F.Fab")
		)
		(fp_line
			(start -0.12065 -0.305054)
			(end -0.12065 -0.2794)
			(stroke
				(width 0.1)
				(type default)
			)
			(layer "F.Fab")
		)
		(fp_line
			(start -0.12065 -0.2794)
			(end 0.12065 -0.2794)
			(stroke
				(width 0.1)
				(type default)
			)
			(layer "F.Fab")
		)
		(fp_line
			(start -0.12065 0.2794)
			(end -0.12065 0.3048)
			(stroke
				(width 0.1)
				(type default)
			)
			(layer "F.Fab")
		)
		(fp_line
			(start -0.12065 0.3048)
			(end -0.67945 0.3048)
			(stroke
				(width 0.1)
				(type default)
			)
			(layer "F.Fab")
		)
		(fp_line
			(start 0.120396 0.2794)
			(end -0.12065 0.2794)
			(stroke
				(width 0.1)
				(type default)
			)
			(layer "F.Fab")
		)
		(fp_line
			(start 0.120396 0.3048)
			(end 0.120396 0.2794)
			(stroke
				(width 0.1)
				(type default)
			)
			(layer "F.Fab")
		)
		(fp_line
			(start 0.12065 -0.3048)
			(end 0.67945 -0.3048)
			(stroke
				(width 0.1)
				(type default)
			)
			(layer "F.Fab")
		)
		(fp_line
			(start 0.12065 -0.2794)
			(end 0.12065 -0.3048)
			(stroke
				(width 0.1)
				(type default)
			)
			(layer "F.Fab")
		)
		(fp_line
			(start 0.67945 -0.3048)
			(end 0.67945 0.3048)
			(stroke
				(width 0.1)
				(type default)
			)
			(layer "F.Fab")
		)
		(fp_line
			(start 0.67945 0.3048)
			(end 0.120396 0.3048)
			(stroke
				(width 0.1)
				(type default)
			)
			(layer "F.Fab")
		)
		(pad "1" smd circle
			(at -0.40005 0)
			(size 0 0)
			(layers "F.Cu" "F.Mask" "F.Paste")
			(net "P3V3_AUX")
		)
		(pad "2" smd circle
			(at 0.40005 0)
			(size 0 0)
			(layers "F.Cu" "F.Mask" "F.Paste")
			(net "SMB_BIC_I2C9_MUX0_SSD3_R_SDA")
		)
	)
)
